# SCM (Grand Teton) — schematic netlist excerpt (pin names and nets, part order shuffled) for the footprints in the layout excerpt that follows; sources: Cadence DE-HDL packaged netlist, KiCad conversion of 12092022_DA0F0TMDCD0_F0T_Management_Board_D_brd_V3_OCP.brd

R685  Q_RES  1K 1% EMPTY  pkg 0402LF  page 14 : A = BMC_EMMC_CD_N ; B = GND

DB1  TDR_3P  EMPTY  pkg TH2  page 60
  GND  = T_GND
  IO1  = TDR_SE_50_OHM_TOP
  IO2  = TDR_SE_50_OHM_TOP

C318  Q_CAP  0.1UF 25V 10% X7R  pkg 0402  page 34 : A = P3V3_AUX ; B = GND

(kicad_pcb
	(version 20260206)
	(generator "pcbnew")
	(generator_version "10.0")
	(general
		(thickness 1.6)
		(legacy_teardrops no)
	)
	(paper "A4")
	(title_block
		(title "12092022_DA0F0TMDCD0_F0T_Management_Board_D_brd_V3_OCP.brd")
		(comment 1 "Grand Teton / footprints 814-816 of 1440")
	)
	(layers
		(0 "F.Cu" signal "TOP")
		(4 "In1.Cu" signal "GND")
		(6 "In2.Cu" signal "IN1")
		(8 "In3.Cu" signal "GND1")
		(10 "In4.Cu" signal "IN2")
		(12 "In5.Cu" signal "VCC")
		(14 "In6.Cu" signal "VCC1")
		(16 "In7.Cu" signal "IN3")
		(18 "In8.Cu" signal "GND2")
		(20 "In9.Cu" signal "IN4")
		(22 "In10.Cu" signal "GND3")
		(2 "B.Cu" signal "BOTTOM")
		(9 "F.Adhes" user "F.Adhesive")
		(11 "B.Adhes" user "B.Adhesive")
		(13 "F.Paste" user "Package Geometry/Pastemask Top")
		(15 "B.Paste" user "Package Geometry/Pastemask Bottom")
		(5 "F.SilkS" user "Ref Des/Silkscreen Top")
		(7 "B.SilkS" user "Ref Des/Silkscreen Bottom")
		(1 "F.Mask" user "Board Geometry/Soldermask Top")
		(3 "B.Mask" user "Board Geometry/Soldermask Bottom")
		(17 "Dwgs.User" user "User.Drawings")
		(19 "Cmts.User" user "User.Comments")
		(21 "Eco1.User" user "User.Eco1")
		(23 "Eco2.User" user "User.Eco2")
		(25 "Edge.Cuts" user "Board Geometry/Outline")
		(27 "Margin" user)
		(31 "F.CrtYd" user "Package Geometry/Place Bound Top")
		(29 "B.CrtYd" user "Package Geometry/Place Bound Bottom")
		(35 "F.Fab" user "Ref Des/Assembly Top")
		(33 "B.Fab" user "Ref Des/Assembly Bottom")
	)
	(footprint ""
		(layer "B.Cu")
		(at 71.599806 -72.047608 -90)
		(property "Reference" "R685"
			(at 0 0 90)
			(layer "B.SilkS")
			(hide yes)
			(effects
				(font
					(size 1.27 1.27)
				)
				(justify mirror)
			)
		)
		(property "Value" ""
			(at 0 0 90)
			(layer "B.Fab")
			(effects
				(font
					(size 1.27 1.27)
				)
				(justify mirror)
			)
		)
		(duplicate_pad_numbers_are_jumpers no)
		(fp_line
			(start -0.7874 0.4064)
			(end 0.7874 0.4064)
			(stroke
				(width 0.1524)
				(type default)
			)
			(layer "B.SilkS")
		)
		(fp_line
			(start 0.7874 0.4064)
			(end 0.7874 -0.4064)
			(stroke
				(width 0.1524)
				(type default)
			)
			(layer "B.SilkS")
		)
		(fp_line
			(start -0.7874 -0.4064)
			(end -0.7874 0.4064)
			(stroke
				(width 0.1524)
				(type default)
			)
			(layer "B.SilkS")
		)
		(fp_line
			(start 0.7874 -0.4064)
			(end -0.7874 -0.4064)
			(stroke
				(width 0.1524)
				(type default)
			)
			(layer "B.SilkS")
		)
		(fp_line
			(start -0.67945 0.3048)
			(end -0.120396 0.3048)
			(stroke
				(width 0.1)
				(type default)
			)
			(layer "B.Fab")
		)
		(fp_line
			(start -0.120396 0.3048)
			(end -0.120396 0.2794)
			(stroke
				(width 0.1)
				(type default)
			)
			(layer "B.Fab")
		)
		(fp_line
			(start 0.12065 0.3048)
			(end 0.67945 0.3048)
			(stroke
				(width 0.1)
				(type default)
			)
			(layer "B.Fab")
		)
		(fp_line
			(start 0.67945 0.3048)
			(end 0.67945 -0.305054)
			(stroke
				(width 0.1)
				(type default)
			)
			(layer "B.Fab")
		)
		(fp_line
			(start -0.120396 0.2794)
			(end 0.12065 0.2794)
			(stroke
				(width 0.1)
				(type default)
			)
			(layer "B.Fab")
		)
		(fp_line
			(start 0.12065 0.2794)
			(end 0.12065 0.3048)
			(stroke
				(width 0.1)
				(type default)
			)
			(layer "B.Fab")
		)
		(fp_line
			(start -0.12065 -0.2794)
			(end -0.12065 -0.3048)
			(stroke
				(width 0.1)
				(type default)
			)
			(layer "B.Fab")
		)
		(fp_line
			(start 0.12065 -0.2794)
			(end -0.12065 -0.2794)
			(stroke
				(width 0.1)
				(type default)
			)
			(layer "B.Fab")
		)
		(fp_line
			(start -0.67945 -0.3048)
			(end -0.67945 0.3048)
			(stroke
				(width 0.1)
				(type default)
			)
			(layer "B.Fab")
		)
		(fp_line
			(start -0.12065 -0.3048)
			(end -0.67945 -0.3048)
			(stroke
				(width 0.1)
				(type default)
			)
			(layer "B.Fab")
		)
		(fp_line
			(start 0.12065 -0.305054)
			(end 0.12065 -0.2794)
			(stroke
				(width 0.1)
				(type default)
			)
			(layer "B.Fab")
		)
		(fp_line
			(start 0.67945 -0.305054)
			(end 0.12065 -0.305054)
			(stroke
				(width 0.1)
				(type default)
			)
			(layer "B.Fab")
		)
		(pad "1" smd circle
			(at 0.40005 0 90)
			(size 0 0)
			(layers "B.Cu" "B.Mask" "B.Paste")
			(net "BMC_EMMC_CD_N")
		)
		(pad "2" smd circle
			(at -0.40005 0 90)
			(size 0 0)
			(layers "B.Cu" "B.Mask" "B.Paste")
			(net "GND")
		)
	)
	(footprint ""
		(layer "B.Cu")
		(at 19.6342 -75.3618 180)
		(property "Reference" "C318"
			(at 0 0 0)
			(layer "B.SilkS")
			(hide yes)
			(effects
				(font
					(size 1.27 1.27)
				)
				(justify mirror)
			)
		)
		(property "Value" ""
			(at 0 0 0)
			(layer "B.Fab")
			(effects
				(font
					(size 1.27 1.27)
				)
				(justify mirror)
			)
		)
		(duplicate_pad_numbers_are_jumpers no)
		(fp_line
			(start 0.7874 0.4064)
			(end 0.7874 -0.4064)
			(stroke
				(width 0.1524)
				(type default)
			)
			(layer "B.SilkS")
		)
		(fp_line
			(start 0.7874 -0.4064)
			(end -0.7874 -0.4064)
			(stroke
				(width 0.1524)
				(type default)
			)
			(layer "B.SilkS")
		)
		(fp_line
			(start -0.7874 0.4064)
			(end 0.7874 0.4064)
			(stroke
				(width 0.1524)
				(type default)
			)
			(layer "B.SilkS")
		)
		(fp_line
			(start -0.7874 -0.4064)
			(end -0.7874 0.4064)
			(stroke
				(width 0.1524)
				(type default)
			)
			(layer "B.SilkS")
		)
		(fp_line
			(start 0.67945 0.3048)
			(end 0.67945 -0.305054)
			(stroke
				(width 0.1)
				(type default)
			)
			(layer "B.Fab")
		)
		(fp_line
			(start 0.67945 -0.305054)
			(end 0.12065 -0.305054)
			(stroke
				(width 0.1)
				(type default)
			)
			(layer "B.Fab")
		)
		(fp_line
			(start 0.12065 0.3048)
			(end 0.67945 0.3048)
			(stroke
				(width 0.1)
				(type default)
			)
			(layer "B.Fab")
		)
		(fp_line
			(start 0.12065 0.2794)
			(end 0.12065 0.3048)
			(stroke
				(width 0.1)
				(type default)
			)
			(layer "B.Fab")
		)
		(fp_line
			(start 0.12065 -0.2794)
			(end -0.12065 -0.2794)
			(stroke
				(width 0.1)
				(type default)
			)
			(layer "B.Fab")
		)
		(fp_line
			(start 0.12065 -0.305054)
			(end 0.12065 -0.2794)
			(stroke
				(width 0.1)
				(type default)
			)
			(layer "B.Fab")
		)
		(fp_line
			(start -0.120396 0.3048)
			(end -0.120396 0.2794)
			(stroke
				(width 0.1)
				(type default)
			)
			(layer "B.Fab")
		)
		(fp_line
			(start -0.120396 0.2794)
			(end 0.12065 0.2794)
			(stroke
				(width 0.1)
				(type default)
			)
			(layer "B.Fab")
		)
		(fp_line
			(start -0.12065 -0.2794)
			(end -0.12065 -0.3048)
			(stroke
				(width 0.1)
				(type default)
			)
			(layer "B.Fab")
		)
		(fp_line
			(start -0.12065 -0.3048)
			(end -0.67945 -0.3048)
			(stroke
				(width 0.1)
				(type default)
			)
			(layer "B.Fab")
		)
		(fp_line
			(start -0.67945 0.3048)
			(end -0.120396 0.3048)
			(stroke
				(width 0.1)
				(type default)
			)
			(layer "B.Fab")
		)
		(fp_line
			(start -0.67945 -0.3048)
			(end -0.67945 0.3048)
			(stroke
				(width 0.1)
				(type default)
			)
			(layer "B.Fab")
		)
		(pad "1" smd circle
			(at 0.40005 0)
			(size 0 0)
			(layers "B.Cu" "B.Mask" "B.Paste")
			(net "P3V3_AUX")
		)
		(pad "2" smd circle
			(at -0.40005 0)
			(size 0 0)
			(layers "B.Cu" "B.Mask" "B.Paste")
			(net "GND")
		)
	)
	(footprint ""
		(layer "B.Cu")
		(at -7.874 -109.728 180)
		(property "Reference" "DB1"
			(at 1.7526 -5.76707 0)
			(unlocked yes)
			(layer "B.SilkS")
			(effects
				(font
					(size 0.7874 0.5842)
					(thickness 0.1524)
				)
				(justify left mirror)
			)
		)
		(property "Value" ""
			(at 0 0 0)
			(layer "B.Fab")
			(effects
				(font
					(size 1.27 1.27)
				)
				(justify mirror)
			)
		)
		(duplicate_pad_numbers_are_jumpers no)
		(fp_line
			(start 3.330702 -4.771136)
			(end -3.330702 -4.771136)
			(stroke
				(width 0.1524)
				(type default)
			)
			(layer "B.SilkS")
		)
		(fp_line
			(start 0 4.011168)
			(end 3.330702 -4.771136)
			(stroke
				(width 0.1524)
				(type default)
			)
			(layer "B.SilkS")
		)
		(fp_line
			(start -3.330702 -4.771136)
			(end 0 4.011168)
			(stroke
				(width 0.1524)
				(type default)
			)
			(layer "B.SilkS")
		)
		(fp_line
			(start 3.330702 -4.771136)
			(end -3.330702 -4.771136)
			(stroke
				(width 0.1)
				(type default)
			)
			(layer "B.Fab")
		)
		(fp_line
			(start 0 4.011168)
			(end 3.330702 -4.771136)
			(stroke
				(width 0.1)
				(type default)
			)
			(layer "B.Fab")
		)
		(fp_line
			(start -3.330702 -4.771136)
			(end 0 4.011168)
			(stroke
				(width 0.1)
				(type default)
			)
			(layer "B.Fab")
		)
		(pad "1" thru_hole circle
			(at 0 0)
			(size 2.159 2.159)
			(drill 1.7018)
			(layers "*.Cu" "*.Mask")
			(remove_unused_layers no)
			(net "T_GND")
			(clearance 0.0254)
			(thermal_gap 0.0254)
		)
		(pad "2" thru_hole circle
			(at 1.27 -3.348736)
			(size 2.159 2.159)
			(drill 1.7018)
			(layers "*.Cu" "*.Mask")
			(remove_unused_layers no)
			(net "TDR_SE_50_OHM_TOP")
			(clearance 0.0254)
			(thermal_gap 0.0254)
		)
		(pad "3" thru_hole circle
			(at -1.27 -3.348736)
			(size 2.159 2.159)
			(drill 1.7018)
			(layers "*.Cu" "*.Mask")
			(remove_unused_layers no)
			(net "TDR_SE_50_OHM_TOP")
			(clearance 0.0254)
			(thermal_gap 0.0254)
		)
	)
)
